# T6G (Grand Teton) — schematic netlist excerpt (pin names and nets, part order shuffled) for the footprints in the layout excerpt that follows; sources: Cadence DE-HDL packaged netlist, KiCad conversion of 04192023_DAF0TMB3IC0_F0TG_MB_C_brd_V02_OCP.brd

PR155  Q_RES  1.5 1% EMPTY  pkg 0402LF  page 203 : A = SW_PVDDCR_CPU1_P0_SW6_RC ; B = GND
PR3781  Q_RES  845 1% CHIP  pkg 0402LF  page 134 : A = P12V_OCP_SENSE_1 ; B = GND

(kicad_pcb
	(version 20260206)
	(generator "pcbnew")
	(generator_version "10.0")
	(general
		(thickness 1.6)
		(legacy_teardrops no)
	)
	(paper "A4")
	(title_block
		(title "04192023_DAF0TMB3IC0_F0TG_MB_C_brd_V02_OCP.brd")
		(comment 1 "Grand Teton / footprints 347-348 of 8354")
	)
	(layers
		(0 "F.Cu" signal "TOP")
		(4 "In1.Cu" signal "GND")
		(6 "In2.Cu" signal "IN1")
		(8 "In3.Cu" signal "GND1")
		(10 "In4.Cu" signal "IN2")
		(12 "In5.Cu" signal "GND2")
		(14 "In6.Cu" signal "IN3")
		(16 "In7.Cu" signal "GND3")
		(18 "In8.Cu" signal "VCC")
		(20 "In9.Cu" signal "VCC1")
		(22 "In10.Cu" signal "GND4")
		(24 "In11.Cu" signal "IN4")
		(26 "In12.Cu" signal "GND5")
		(28 "In13.Cu" signal "IN5")
		(30 "In14.Cu" signal "GND6")
		(32 "In15.Cu" signal "IN6")
		(34 "In16.Cu" signal "GND7")
		(2 "B.Cu" signal "BOTTOM")
		(9 "F.Adhes" user "F.Adhesive")
		(11 "B.Adhes" user "B.Adhesive")
		(13 "F.Paste" user "Package Geometry/Pastemask Top")
		(15 "B.Paste" user "Package Geometry/Pastemask Bottom")
		(5 "F.SilkS" user "Ref Des/Silkscreen Top")
		(7 "B.SilkS" user "Ref Des/Silkscreen Bottom")
		(1 "F.Mask" user "Board Geometry/Soldermask Top")
		(3 "B.Mask" user "Board Geometry/Soldermask Bottom")
		(17 "Dwgs.User" user "User.Drawings")
		(19 "Cmts.User" user "User.Comments")
		(21 "Eco1.User" user "User.Eco1")
		(23 "Eco2.User" user "User.Eco2")
		(25 "Edge.Cuts" user "Board Geometry/Outline")
		(27 "Margin" user)
		(31 "F.CrtYd" user "Package Geometry/Place Bound Top")
		(29 "B.CrtYd" user "Package Geometry/Place Bound Bottom")
		(35 "F.Fab" user "Ref Des/Assembly Top")
		(33 "B.Fab" user "Ref Des/Assembly Bottom")
	)
	(footprint ""
		(layer "F.Cu")
		(at 447.687192 -22.125178 180)
		(property "Reference" "PR3781"
			(at 0 0 180)
			(layer "F.SilkS")
			(hide yes)
			(effects
				(font
					(size 1.27 1.27)
				)
			)
		)
		(property "Value" ""
			(at 0 0 180)
			(layer "F.Fab")
			(effects
				(font
					(size 1.27 1.27)
				)
			)
		)
		(duplicate_pad_numbers_are_jumpers no)
		(fp_line
			(start 0.7874 0.4064)
			(end -0.7874 0.4064)
			(stroke
				(width 0.1524)
				(type default)
			)
			(layer "F.SilkS")
		)
		(fp_line
			(start 0.7874 -0.4064)
			(end 0.7874 0.4064)
			(stroke
				(width 0.1524)
				(type default)
			)
			(layer "F.SilkS")
		)
		(fp_line
			(start -0.7874 0.4064)
			(end -0.7874 -0.4064)
			(stroke
				(width 0.1524)
				(type default)
			)
			(layer "F.SilkS")
		)
		(fp_line
			(start -0.7874 -0.4064)
			(end 0.7874 -0.4064)
			(stroke
				(width 0.1524)
				(type default)
			)
			(layer "F.SilkS")
		)
		(fp_line
			(start 0.67945 0.3048)
			(end 0.120396 0.3048)
			(stroke
				(width 0.1)
				(type default)
			)
			(layer "F.Fab")
		)
		(fp_line
			(start 0.67945 -0.3048)
			(end 0.67945 0.3048)
			(stroke
				(width 0.1)
				(type default)
			)
			(layer "F.Fab")
		)
		(fp_line
			(start 0.12065 -0.2794)
			(end 0.12065 -0.3048)
			(stroke
				(width 0.1)
				(type default)
			)
			(layer "F.Fab")
		)
		(fp_line
			(start 0.12065 -0.3048)
			(end 0.67945 -0.3048)
			(stroke
				(width 0.1)
				(type default)
			)
			(layer "F.Fab")
		)
		(fp_line
			(start 0.120396 0.3048)
			(end 0.120396 0.2794)
			(stroke
				(width 0.1)
				(type default)
			)
			(layer "F.Fab")
		)
		(fp_line
			(start 0.120396 0.2794)
			(end -0.12065 0.2794)
			(stroke
				(width 0.1)
				(type default)
			)
			(layer "F.Fab")
		)
		(fp_line
			(start -0.12065 0.3048)
			(end -0.67945 0.3048)
			(stroke
				(width 0.1)
				(type default)
			)
			(layer "F.Fab")
		)
		(fp_line
			(start -0.12065 0.2794)
			(end -0.12065 0.3048)
			(stroke
				(width 0.1)
				(type default)
			)
			(layer "F.Fab")
		)
		(fp_line
			(start -0.12065 -0.2794)
			(end 0.12065 -0.2794)
			(stroke
				(width 0.1)
				(type default)
			)
			(layer "F.Fab")
		)
		(fp_line
			(start -0.12065 -0.305054)
			(end -0.12065 -0.2794)
			(stroke
				(width 0.1)
				(type default)
			)
			(layer "F.Fab")
		)
		(fp_line
			(start -0.67945 0.3048)
			(end -0.67945 -0.305054)
			(stroke
				(width 0.1)
				(type default)
			)
			(layer "F.Fab")
		)
		(fp_line
			(start -0.67945 -0.305054)
			(end -0.12065 -0.305054)
			(stroke
				(width 0.1)
				(type default)
			)
			(layer "F.Fab")
		)
		(pad "1" smd circle
			(at -0.40005 0 180)
			(size 0 0)
			(layers "F.Cu" "F.Mask" "F.Paste")
			(net "P12V_OCP_SENSE_1")
		)
		(pad "2" smd circle
			(at 0.40005 0 180)
			(size 0 0)
			(layers "F.Cu" "F.Mask" "F.Paste")
			(net "GND")
		)
	)
	(footprint ""
		(layer "F.Cu")
		(at 347.98889 -338.200238 90)
		(property "Reference" "PR155"
			(at 0 0 90)
			(layer "F.SilkS")
			(hide yes)
			(effects
				(font
					(size 1.27 1.27)
				)
			)
		)
		(property "Value" ""
			(at 0 0 90)
			(layer "F.Fab")
			(effects
				(font
					(size 1.27 1.27)
				)
			)
		)
		(duplicate_pad_numbers_are_jumpers no)
		(fp_line
			(start 0.7874 -0.4064)
			(end 0.7874 0.4064)
			(stroke
				(width 0.1524)
				(type default)
			)
			(layer "F.SilkS")
		)
		(fp_line
			(start -0.7874 -0.4064)
			(end 0.7874 -0.4064)
			(stroke
				(width 0.1524)
				(type default)
			)
			(layer "F.SilkS")
		)
		(fp_line
			(start 0.7874 0.4064)
			(end -0.7874 0.4064)
			(stroke
				(width 0.1524)
				(type default)
			)
			(layer "F.SilkS")
		)
		(fp_line
			(start -0.7874 0.4064)
			(end -0.7874 -0.4064)
			(stroke
				(width 0.1524)
				(type default)
			)
			(layer "F.SilkS")
		)
		(fp_line
			(start -0.12065 -0.305054)
			(end -0.12065 -0.2794)
			(stroke
				(width 0.1)
				(type default)
			)
			(layer "F.Fab")
		)
		(fp_line
			(start -0.67945 -0.305054)
			(end -0.12065 -0.305054)
			(stroke
				(width 0.1)
				(type default)
			)
			(layer "F.Fab")
		)
		(fp_line
			(start 0.67945 -0.3048)
			(end 0.67945 0.3048)
			(stroke
				(width 0.1)
				(type default)
			)
			(layer "F.Fab")
		)
		(fp_line
			(start 0.12065 -0.3048)
			(end 0.67945 -0.3048)
			(stroke
				(width 0.1)
				(type default)
			)
			(layer "F.Fab")
		)
		(fp_line
			(start 0.12065 -0.2794)
			(end 0.12065 -0.3048)
			(stroke
				(width 0.1)
				(type default)
			)
			(layer "F.Fab")
		)
		(fp_line
			(start -0.12065 -0.2794)
			(end 0.12065 -0.2794)
			(stroke
				(width 0.1)
				(type default)
			)
			(layer "F.Fab")
		)
		(fp_line
			(start 0.120396 0.2794)
			(end -0.12065 0.2794)
			(stroke
				(width 0.1)
				(type default)
			)
			(layer "F.Fab")
		)
		(fp_line
			(start -0.12065 0.2794)
			(end -0.12065 0.3048)
			(stroke
				(width 0.1)
				(type default)
			)
			(layer "F.Fab")
		)
		(fp_line
			(start 0.67945 0.3048)
			(end 0.120396 0.3048)
			(stroke
				(width 0.1)
				(type default)
			)
			(layer "F.Fab")
		)
		(fp_line
			(start 0.120396 0.3048)
			(end 0.120396 0.2794)
			(stroke
				(width 0.1)
				(type default)
			)
			(layer "F.Fab")
		)
		(fp_line
			(start -0.12065 0.3048)
			(end -0.67945 0.3048)
			(stroke
				(width 0.1)
				(type default)
			)
			(layer "F.Fab")
		)
		(fp_line
			(start -0.67945 0.3048)
			(end -0.67945 -0.305054)
			(stroke
				(width 0.1)
				(type default)
			)
			(layer "F.Fab")
		)
		(pad "1" smd circle
			(at -0.40005 0 90)
			(size 0 0)
			(layers "F.Cu" "F.Mask" "F.Paste")
			(net "SW_PVDDCR_CPU1_P0_SW6_RC")
		)
		(pad "2" smd circle
			(at 0.40005 0 90)
			(size 0 0)
			(layers "F.Cu" "F.Mask" "F.Paste")
			(net "GND")
		)
	)
)
